(kicad_pcb
	(version 20260206)
	(generator "pcbnew")
	(generator_version "10.0")
	(general
		(thickness 1.6)
		(legacy_teardrops no)
	)
	(paper "A4")
	(title_block
		(title "peb — Lightning_PEB_BRD.brd")
		(comment 1 "Lightning (Wiwynn / Facebook NVMe JBOF) / footprints 935-942 of 2563")
	)
	(layers
		(0 "F.Cu" signal "TOP")
		(4 "In1.Cu" signal "L2GND")
		(6 "In2.Cu" signal "L3")
		(8 "In3.Cu" signal "L4VCC")
		(10 "In4.Cu" signal "L5VCC")
		(12 "In5.Cu" signal "L6")
		(14 "In6.Cu" signal "L7GND")
		(2 "B.Cu" signal "BOTTOM")
		(9 "F.Adhes" user "F.Adhesive")
		(11 "B.Adhes" user "B.Adhesive")
		(13 "F.Paste" user "Package Geometry/Pastemask Top")
		(15 "B.Paste" user "Package Geometry/Pastemask Bottom")
		(5 "F.SilkS" user "Ref Des/Silkscreen Top")
		(7 "B.SilkS" user "Ref Des/Silkscreen Bottom")
		(1 "F.Mask" user "Board Geometry/Soldermask Top")
		(3 "B.Mask" user "Board Geometry/Soldermask Bottom")
		(17 "Dwgs.User" user "User.Drawings")
		(19 "Cmts.User" user "User.Comments")
		(21 "Eco1.User" user "User.Eco1")
		(23 "Eco2.User" user "User.Eco2")
		(25 "Edge.Cuts" user "Board Geometry/Outline")
		(27 "Margin" user)
		(31 "F.CrtYd" user "Package Geometry/Place Bound Top")
		(29 "B.CrtYd" user "Package Geometry/Place Bound Bottom")
		(35 "F.Fab" user "Ref Des/Assembly Top")
		(33 "B.Fab" user "Ref Des/Assembly Bottom")
	)
	(footprint ""
		(layer "F.Cu")
		(at 30.9626 -185.3692 180)
		(property "Reference" "U34"
			(at 0 0 180)
			(layer "F.SilkS")
			(hide yes)
			(effects
				(font
					(size 1.27 1.27)
				)
			)
		)
		(property "Value" "PCA9511ADP-T-GP"
			(at 0 -13.1572 180)
			(unlocked yes)
			(layer "F.Fab")
			(hide yes)
			(effects
				(font
					(size 1.016 1.016)
					(thickness 0.1524)
				)
			)
		)
		(property "Device Type" "SSOIC8-2H44"
			(at 0 -15.1892 180)
			(unlocked yes)
			(layer "F.Fab")
			(hide yes)
			(effects
				(font
					(size 1.016 1.016)
					(thickness 0.1524)
				)
			)
		)
		(duplicate_pad_numbers_are_jumpers no)
		(fp_line
			(start 1.0922 1.016)
			(end -1.9304 1.016)
			(stroke
				(width 0.1524)
				(type default)
			)
			(layer "F.SilkS")
		)
		(fp_line
			(start 1.0922 -1.016)
			(end 1.0922 1.016)
			(stroke
				(width 0.1524)
				(type default)
			)
			(layer "F.SilkS")
		)
		(fp_line
			(start -1.524 0)
			(end -1.9304 0.4064)
			(stroke
				(width 0.1524)
				(type default)
			)
			(layer "F.SilkS")
		)
		(fp_line
			(start -1.524 0)
			(end -1.9304 -0.4064)
			(stroke
				(width 0.1524)
				(type default)
			)
			(layer "F.SilkS")
		)
		(fp_line
			(start -1.7018 1.0414)
			(end -1.7018 2.9718)
			(stroke
				(width 0.635)
				(type default)
			)
			(layer "F.SilkS")
		)
		(fp_line
			(start -1.9304 1.016)
			(end -1.9304 -1.016)
			(stroke
				(width 0.1524)
				(type default)
			)
			(layer "F.SilkS")
		)
		(fp_line
			(start -1.9304 -1.016)
			(end 1.0922 -1.016)
			(stroke
				(width 0.1524)
				(type default)
			)
			(layer "F.SilkS")
		)
		(fp_poly
			(pts
				(xy -1.1938 -1.016) (xy 1.0922 -1.016) (xy 1.0922 1.016) (xy -1.1938 1.016)
			)
			(stroke
				(width 0)
				(type default)
			)
			(fill yes)
			(layer "F.SilkS")
		)
		(fp_rect
			(start -2.0066 3.3401)
			(end 2.0066 -3.3401)
			(stroke
				(width 0)
				(type default)
			)
			(fill no)
			(layer "F.CrtYd")
		)
		(fp_poly
			(pts
				(xy -2.0066 -3.3401) (xy 2.0066 -3.3401) (xy 2.0066 3.3401) (xy -2.0066 3.3401)
			)
			(stroke
				(width 0)
				(type default)
			)
			(fill no)
			(layer "F.Fab")
		)
		(pad "1" smd rect
			(at -0.97536 2.0701 180)
			(size 0.4064 1.524)
			(layers "F.Cu" "F.Mask" "F.Paste")
			(net "I2C5_BUFF_EN")
		)
		(pad "2" smd rect
			(at -0.32512 2.0701 180)
			(size 0.4064 1.524)
			(layers "F.Cu" "F.Mask" "F.Paste")
			(net "BUF_I2C5_SCL_R")
		)
		(pad "3" smd rect
			(at 0.32512 2.0701 180)
			(size 0.4064 1.524)
			(layers "F.Cu" "F.Mask" "F.Paste")
			(net "BMC_I2C5_SCL_R")
		)
		(pad "4" smd rect
			(at 0.97536 2.0701 180)
			(size 0.4064 1.524)
			(layers "F.Cu" "F.Mask" "F.Paste")
			(net "GND")
		)
		(pad "5" smd rect
			(at 0.97536 -2.0701 180)
			(size 0.4064 1.524)
			(layers "F.Cu" "F.Mask" "F.Paste")
			(net "BMC_I2C5_BUF_READY")
		)
		(pad "6" smd rect
			(at 0.32512 -2.0701 180)
			(size 0.4064 1.524)
			(layers "F.Cu" "F.Mask" "F.Paste")
			(net "BMC_I2C5_SDA_R")
		)
		(pad "7" smd rect
			(at -0.32512 -2.0701 180)
			(size 0.4064 1.524)
			(layers "F.Cu" "F.Mask" "F.Paste")
			(net "BUF_I2C5_SDA_R")
		)
		(pad "8" smd rect
			(at -0.97536 -2.0701 180)
			(size 0.4064 1.524)
			(layers "F.Cu" "F.Mask" "F.Paste")
			(net "P3V3_STBY")
		)
	)
	(footprint ""
		(layer "F.Cu")
		(at 26.4287 -33.89884)
		(property "Reference" "C420"
			(at 0 0 0)
			(layer "F.SilkS")
			(hide yes)
			(effects
				(font
					(size 1.27 1.27)
				)
			)
		)
		(property "Value" "SCD1U16V2KX-3GP"
			(at 1.1811 -2.7051 0)
			(unlocked yes)
			(layer "F.Fab")
			(hide yes)
			(effects
				(font
					(size 1.016 1.016)
					(thickness 0.1524)
				)
			)
		)
		(property "Device Type" "C402H22"
			(at 1.1811 -4.2291 0)
			(unlocked yes)
			(layer "F.Fab")
			(hide yes)
			(effects
				(font
					(size 1.016 1.016)
					(thickness 0.1524)
				)
			)
		)
		(duplicate_pad_numbers_are_jumpers no)
		(fp_rect
			(start -0.4318 0.9525)
			(end 0.4318 -0.9525)
			(stroke
				(width 0)
				(type default)
			)
			(fill no)
			(layer "F.CrtYd")
		)
		(fp_rect
			(start -0.4318 0.9525)
			(end 0.4318 -0.9525)
			(stroke
				(width 0)
				(type default)
			)
			(fill no)
			(layer "F.Fab")
		)
		(pad "1" smd custom
			(at 0 -0.4445)
			(size 0.1524 0.1524)
			(layers "F.Cu" "F.Mask" "F.Paste")
			(net "LED_MDI0_100M_N_R")
			(options
				(clearance outline)
				(anchor circle)
			)
			(primitives
				(gr_poly
					(pts
						(arc
							(start 0.3048 -0.2032)
							(mid 0.275042 -0.275042)
							(end 0.2032 -0.3048)
						)
						(arc
							(start -0.2032 -0.3048)
							(mid -0.275042 -0.275042)
							(end -0.3048 -0.2032)
						)
						(arc
							(start -0.3048 0.2032)
							(mid -0.275042 0.275042)
							(end -0.2032 0.3048)
						)
						(arc
							(start 0.2032 0.3048)
							(mid 0.275042 0.275042)
							(end 0.3048 0.2032)
						)
					)
					(width 0)
					(fill yes)
				)
			)
		)
		(pad "2" smd custom
			(at 0 0.4445)
			(size 0.1524 0.1524)
			(layers "F.Cu" "F.Mask" "F.Paste")
			(net "GND")
			(options
				(clearance outline)
				(anchor circle)
			)
			(primitives
				(gr_poly
					(pts
						(arc
							(start 0.3048 -0.2032)
							(mid 0.275042 -0.275042)
							(end 0.2032 -0.3048)
						)
						(arc
							(start -0.2032 -0.3048)
							(mid -0.275042 -0.275042)
							(end -0.3048 -0.2032)
						)
						(arc
							(start -0.3048 0.2032)
							(mid -0.275042 0.275042)
							(end -0.2032 0.3048)
						)
						(arc
							(start 0.2032 0.3048)
							(mid 0.275042 0.275042)
							(end 0.3048 0.2032)
						)
					)
					(width 0)
					(fill yes)
				)
			)
		)
	)
	(footprint ""
		(layer "F.Cu")
		(at 301.244 -68.834 180)
		(property "Reference" "C456"
			(at 0 0 180)
			(layer "F.SilkS")
			(hide yes)
			(effects
				(font
					(size 1.27 1.27)
				)
			)
		)
		(property "Value" "SC100U4V5MX-1-GP"
			(at -0.0762 -6.1214 180)
			(unlocked yes)
			(layer "F.Fab")
			(hide yes)
			(effects
				(font
					(size 1.016 1.016)
					(thickness 0.1524)
				)
			)
		)
		(property "Device Type" "C805H58"
			(at -0.0762 -8.1534 180)
			(unlocked yes)
			(layer "F.Fab")
			(hide yes)
			(effects
				(font
					(size 1.016 1.016)
					(thickness 0.1524)
				)
			)
		)
		(duplicate_pad_numbers_are_jumpers no)
		(fp_line
			(start 0.635 0)
			(end -0.635 0)
			(stroke
				(width 0.508)
				(type default)
			)
			(layer "F.SilkS")
		)
		(fp_rect
			(start -0.9652 1.778)
			(end 0.9652 -1.778)
			(stroke
				(width 0)
				(type default)
			)
			(fill no)
			(layer "F.CrtYd")
		)
		(fp_poly
			(pts
				(xy -0.9652 -1.778) (xy 0.9652 -1.778) (xy 0.9652 1.778) (xy -0.9652 1.778)
			)
			(stroke
				(width 0)
				(type default)
			)
			(fill no)
			(layer "F.Fab")
		)
		(pad "1" smd rect
			(at 0 -0.9652 180)
			(size 1.397 1.143)
			(layers "F.Cu" "F.Mask" "F.Paste")
			(net "DUT_VDD")
		)
		(pad "2" smd rect
			(at 0 0.9652 180)
			(size 1.397 1.143)
			(layers "F.Cu" "F.Mask" "F.Paste")
			(net "GND")
		)
	)
	(footprint ""
		(layer "F.Cu")
		(at 33.0962 -212.09 90)
		(property "Reference" "C7274"
			(at 0 0 90)
			(layer "F.SilkS")
			(hide yes)
			(effects
				(font
					(size 1.27 1.27)
				)
			)
		)
		(property "Value" "SCD1U25V3KX-GP"
			(at 0 -2.8194 90)
			(unlocked yes)
			(layer "F.Fab")
			(hide yes)
			(effects
				(font
					(size 1.016 1.016)
					(thickness 0.1524)
				)
			)
		)
		(property "Device Type" "C603H36"
			(at 0 -4.3434 90)
			(unlocked yes)
			(layer "F.Fab")
			(hide yes)
			(effects
				(font
					(size 1.016 1.016)
					(thickness 0.1524)
				)
			)
		)
		(duplicate_pad_numbers_are_jumpers no)
		(fp_line
			(start 0.508 0)
			(end -0.508 0)
			(stroke
				(width 0.2032)
				(type default)
			)
			(layer "F.SilkS")
		)
		(fp_rect
			(start -0.5842 1.3335)
			(end 0.5842 -1.3335)
			(stroke
				(width 0)
				(type default)
			)
			(fill no)
			(layer "F.CrtYd")
		)
		(fp_rect
			(start -0.5842 1.3335)
			(end 0.5842 -1.3335)
			(stroke
				(width 0)
				(type default)
			)
			(fill no)
			(layer "F.Fab")
		)
		(pad "1" smd custom
			(at 0 -0.762 90)
			(size 0.2159 0.2159)
			(layers "F.Cu" "F.Mask" "F.Paste")
			(net "P12V_PCIE")
			(options
				(clearance outline)
				(anchor circle)
			)
			(primitives
				(gr_poly
					(pts
						(arc
							(start -0.3302 -0.4318)
							(mid -0.402042 -0.402042)
							(end -0.4318 -0.3302)
						)
						(arc
							(start -0.4318 0.3302)
							(mid -0.402042 0.402042)
							(end -0.3302 0.4318)
						)
						(arc
							(start 0.3302 0.4318)
							(mid 0.402042 0.402042)
							(end 0.4318 0.3302)
						)
						(arc
							(start 0.4318 -0.3302)
							(mid 0.402042 -0.402042)
							(end 0.3302 -0.4318)
						)
					)
					(width 0)
					(fill yes)
				)
			)
		)
		(pad "2" smd custom
			(at 0 0.762 90)
			(size 0.2159 0.2159)
			(layers "F.Cu" "F.Mask" "F.Paste")
			(net "GND")
			(options
				(clearance outline)
				(anchor circle)
			)
			(primitives
				(gr_poly
					(pts
						(arc
							(start -0.3302 -0.4318)
							(mid -0.402042 -0.402042)
							(end -0.4318 -0.3302)
						)
						(arc
							(start -0.4318 0.3302)
							(mid -0.402042 0.402042)
							(end -0.3302 0.4318)
						)
						(arc
							(start 0.3302 0.4318)
							(mid 0.402042 0.402042)
							(end 0.4318 0.3302)
						)
						(arc
							(start 0.4318 -0.3302)
							(mid 0.402042 -0.402042)
							(end 0.3302 -0.4318)
						)
					)
					(width 0)
					(fill yes)
				)
			)
		)
	)
	(footprint ""
		(layer "F.Cu")
		(at 59.69 -129.413 -90)
		(property "Reference" "L4"
			(at 0 0 270)
			(layer "F.SilkS")
			(hide yes)
			(effects
				(font
					(size 1.27 1.27)
				)
			)
		)
		(property "Value" "MMZ2012S601ATA1N-GP"
			(at 0 -4.2418 270)
			(unlocked yes)
			(layer "F.Fab")
			(hide yes)
			(effects
				(font
					(size 1.016 1.016)
					(thickness 0.1524)
				)
			)
		)
		(property "Device Type" "L805H42"
			(at 0 -5.7912 270)
			(unlocked yes)
			(layer "F.Fab")
			(hide yes)
			(effects
				(font
					(size 1.016 1.016)
					(thickness 0.1524)
				)
			)
		)
		(duplicate_pad_numbers_are_jumpers no)
		(fp_line
			(start -0.889 1.7018)
			(end -0.889 -1.7018)
			(stroke
				(width 0.1524)
				(type default)
			)
			(layer "F.SilkS")
		)
		(fp_line
			(start 0.889 1.7018)
			(end -0.889 1.7018)
			(stroke
				(width 0.1524)
				(type default)
			)
			(layer "F.SilkS")
		)
		(fp_line
			(start -0.889 -1.7018)
			(end 0.889 -1.7018)
			(stroke
				(width 0.1524)
				(type default)
			)
			(layer "F.SilkS")
		)
		(fp_line
			(start 0.889 -1.7018)
			(end 0.889 1.7018)
			(stroke
				(width 0.1524)
				(type default)
			)
			(layer "F.SilkS")
		)
		(fp_rect
			(start -0.9652 1.778)
			(end 0.9652 -1.778)
			(stroke
				(width 0)
				(type default)
			)
			(fill no)
			(layer "F.CrtYd")
		)
		(fp_rect
			(start -0.9652 1.778)
			(end 0.9652 -1.778)
			(stroke
				(width 0)
				(type default)
			)
			(fill no)
			(layer "F.Fab")
		)
		(pad "1" smd rect
			(at 0 -0.9652 270)
			(size 1.397 1.143)
			(layers "F.Cu" "F.Mask" "F.Paste")
			(net "P3V3_STBY")
		)
		(pad "2" smd rect
			(at 0 0.9652 270)
			(size 1.397 1.143)
			(layers "F.Cu" "F.Mask" "F.Paste")
			(net "ADCAV33")
		)
	)
	(footprint ""
		(layer "F.Cu")
		(at 175.961802 -71.071232 -90)
		(property "Reference" "PG31"
			(at 0 0 270)
			(layer "F.SilkS")
			(hide yes)
			(effects
				(font
					(size 1.27 1.27)
				)
			)
		)
		(property "Value" "GAP-CLOSE-PWR-3-GP"
			(at 0.0254 -6.5786 270)
			(unlocked yes)
			(layer "F.Fab")
			(hide yes)
			(effects
				(font
					(size 1.016 1.016)
					(thickness 0.1524)
				)
			)
		)
		(property "Device Type" "GAP-CLOSE-PWR-3"
			(at 0.0254 -8.255 270)
			(unlocked yes)
			(layer "F.Fab")
			(hide yes)
			(effects
				(font
					(size 1.016 1.016)
					(thickness 0.1524)
				)
			)
		)
		(duplicate_pad_numbers_are_jumpers no)
		(fp_rect
			(start -0.7112 0.4572)
			(end 0.7112 -0.4572)
			(stroke
				(width 0)
				(type default)
			)
			(fill no)
			(layer "F.CrtYd")
		)
		(fp_poly
			(pts
				(xy -0.7112 -0.4572) (xy 0.7112 -0.4572) (xy 0.7112 0.4572) (xy -0.7112 0.4572)
			)
			(stroke
				(width 0)
				(type default)
			)
			(fill no)
			(layer "F.Fab")
		)
		(pad "1" smd rect
			(at -0.3048 0 270)
			(size 0.6604 0.762)
			(layers "F.Cu" "F.Mask" "F.Paste")
			(net "DUT_AVD_TX")
		)
		(pad "2" smd rect
			(at 0.3048 0 270)
			(size 0.6604 0.762)
			(layers "F.Cu" "F.Mask" "F.Paste")
			(net "P0V9")
		)
	)
	(footprint ""
		(layer "F.Cu")
		(at 37.393626 -72.690482 90)
		(property "Reference" "PL1"
			(at 0 0 90)
			(layer "F.SilkS")
			(hide yes)
			(effects
				(font
					(size 1.27 1.27)
				)
			)
		)
		(property "Value" "IND-15UH-87-GP"
			(at -3.8989 1.2954 90)
			(unlocked yes)
			(layer "F.Fab")
			(hide yes)
			(effects
				(font
					(size 1.016 1.016)
					(thickness 0.1524)
				)
			)
		)
		(property "Device Type" "L47474716H158"
			(at -3.8989 -0.2286 90)
			(unlocked yes)
			(layer "F.Fab")
			(hide yes)
			(effects
				(font
					(size 1.016 1.016)
					(thickness 0.1524)
				)
			)
		)
		(duplicate_pad_numbers_are_jumpers no)
		(fp_line
			(start 2.6289 -3.3909)
			(end 2.6289 3.3909)
			(stroke
				(width 0.1524)
				(type default)
			)
			(layer "F.SilkS")
		)
		(fp_line
			(start -2.6289 -3.3909)
			(end 2.6289 -3.3909)
			(stroke
				(width 0.1524)
				(type default)
			)
			(layer "F.SilkS")
		)
		(fp_line
			(start 2.6289 3.3909)
			(end -2.6289 3.3909)
			(stroke
				(width 0.1524)
				(type default)
			)
			(layer "F.SilkS")
		)
		(fp_line
			(start -2.6289 3.3909)
			(end -2.6289 -3.3909)
			(stroke
				(width 0.1524)
				(type default)
			)
			(layer "F.SilkS")
		)
		(fp_rect
			(start -2.3495 2.3495)
			(end 2.3495 -2.3495)
			(stroke
				(width 0)
				(type default)
			)
			(fill no)
			(layer "F.CrtYd")
		)
		(fp_poly
			(pts
				(xy -2.8829 3.4671) (xy -2.8829 -2.3368) (xy -2.3495 -2.3368) (xy -2.3495 2.3495) (xy 2.3495 2.3495)
				(xy 2.3495 -2.3495) (xy -2.8829 -2.3495) (xy -2.8829 -3.4671) (xy 2.8829 -3.4671) (xy 2.8829 3.4671)
			)
			(stroke
				(width 0)
				(type default)
			)
			(fill no)
			(layer "F.CrtYd")
		)
		(fp_poly
			(pts
				(xy -2.8829 3.4671) (xy 2.8829 3.4671) (xy 2.8829 -3.4671) (xy -2.8829 -3.4671)
			)
			(stroke
				(width 0)
				(type default)
			)
			(fill no)
			(layer "F.Fab")
		)
		(pad "1" smd rect
			(at 0 -1.8161 90)
			(size 4.7498 2.6416)
			(layers "F.Cu" "F.Mask" "F.Paste")
			(net "P5V_STBY_LX")
		)
		(pad "2" smd rect
			(at 0 1.8161 90)
			(size 4.7498 2.6416)
			(layers "F.Cu" "F.Mask" "F.Paste")
			(net "P5V_STBY_LR")
		)
	)
	(footprint ""
		(layer "F.Cu")
		(at 51.816 -177.165 180)
		(property "Reference" "R904"
			(at 0 0 180)
			(layer "F.SilkS")
			(hide yes)
			(effects
				(font
					(size 1.27 1.27)
				)
			)
		)
		(property "Value" "0R2J-2-GP"
			(at 0.064008 -3.993896 180)
			(unlocked yes)
			(layer "F.Fab")
			(hide yes)
			(effects
				(font
					(size 1.016 1.016)
					(thickness 0.1524)
				)
			)
		)
		(property "Device Type" "R402H16"
			(at 0.064008 -5.517896 180)
			(unlocked yes)
			(layer "F.Fab")
			(hide yes)
			(effects
				(font
					(size 1.016 1.016)
					(thickness 0.1524)
				)
			)
		)
		(duplicate_pad_numbers_are_jumpers no)
		(fp_line
			(start 0.508 -0.9398)
			(end -0.508 -0.9398)
			(stroke
				(width 0.1524)
				(type default)
			)
			(layer "F.SilkS")
		)
		(fp_line
			(start -0.508 -0.9398)
			(end -0.508 0.9398)
			(stroke
				(width 0.1524)
				(type default)
			)
			(layer "F.SilkS")
		)
		(fp_rect
			(start -0.508 0.9398)
			(end 0.508 -0.9398)
			(stroke
				(width 0)
				(type default)
			)
			(fill no)
			(layer "F.CrtYd")
		)
		(fp_rect
			(start -0.508 0.9398)
			(end 0.508 -0.9398)
			(stroke
				(width 0)
				(type default)
			)
			(fill no)
			(layer "F.Fab")
		)
		(pad "1" smd custom
			(at 0 -0.4445 180)
			(size 0.1397 0.1397)
			(layers "F.Cu" "F.Mask" "F.Paste")
			(net "BMC_I2C8_CLKBUF1_SCL")
			(options
				(clearance outline)
				(anchor circle)
			)
			(primitives
				(gr_poly
					(pts
						(arc
							(start -0.1778 -0.2794)
							(mid -0.249642 -0.249642)
							(end -0.2794 -0.1778)
						)
						(arc
							(start -0.2794 0.1778)
							(mid -0.249642 0.249642)
							(end -0.1778 0.2794)
						)
						(arc
							(start 0.1778 0.2794)
							(mid 0.249642 0.249642)
							(end 0.2794 0.1778)
						)
						(arc
							(start 0.2794 -0.1778)
							(mid 0.249642 -0.249642)
							(end 0.1778 -0.2794)
						)
					)
					(width 0)
					(fill yes)
				)
			)
		)
		(pad "2" smd custom
			(at 0 0.4445 180)
			(size 0.1397 0.1397)
			(layers "F.Cu" "F.Mask" "F.Paste")
			(net "BMC_I2C8_CLKBUF1_SCL_R")
			(options
				(clearance outline)
				(anchor circle)
			)
			(primitives
				(gr_poly
					(pts
						(arc
							(start -0.1778 -0.2794)
							(mid -0.249642 -0.249642)
							(end -0.2794 -0.1778)
						)
						(arc
							(start -0.2794 0.1778)
							(mid -0.249642 0.249642)
							(end -0.1778 0.2794)
						)
						(arc
							(start 0.1778 0.2794)
							(mid 0.249642 0.249642)
							(end 0.2794 0.1778)
						)
						(arc
							(start 0.2794 -0.1778)
							(mid 0.249642 -0.249642)
							(end 0.1778 -0.2794)
						)
					)
					(width 0)
					(fill yes)
				)
			)
		)
	)
)
